# BASEBOARD_FAB2 (Tioga Pass) — schematic netlist excerpt (pin names and nets, part order shuffled) for the footprints in the layout excerpt that follows; sources: Cadence DE-HDL packaged netlist, KiCad conversion of Wiwynn_Tioga_Pass_MB.brd

C7G28  CAPP  470UF 2.5V 20% ALUM  pkg 3018  page 217 : A = PVDDQ_ABC ; B = GND
C7F9  CAP  100.0PF 50V 5% COG  pkg 0402LF  page 231 : A = VR_FB_PVPP_ABC ; B = VR_COMP_PVPP_ABC_3
R8G14  RES  0.0 5% CHIP  pkg 0402  page 189 : A = JTAG_BMC_TMS ; B = JTAG_TMS

(kicad_pcb
	(version 20260206)
	(generator "pcbnew")
	(generator_version "10.0")
	(general
		(thickness 1.6)
		(legacy_teardrops no)
	)
	(paper "A4")
	(title_block
		(title "Wiwynn_Tioga_Pass_MB.brd")
		(comment 1 "Tioga Pass / footprints 2112-2114 of 4770")
	)
	(layers
		(0 "F.Cu" signal "TOP")
		(4 "In1.Cu" signal "L2GND")
		(6 "In2.Cu" signal "L3")
		(8 "In3.Cu" signal "L4GND")
		(10 "In4.Cu" signal "L5")
		(12 "In5.Cu" signal "L6GND")
		(14 "In6.Cu" signal "L7VCC")
		(16 "In7.Cu" signal "L8VCC")
		(18 "In8.Cu" signal "L9GND")
		(20 "In9.Cu" signal "L10")
		(22 "In10.Cu" signal "L11GND")
		(24 "In11.Cu" signal "L12")
		(26 "In12.Cu" signal "L13GND")
		(2 "B.Cu" signal "BOTTOM")
		(9 "F.Adhes" user "F.Adhesive")
		(11 "B.Adhes" user "B.Adhesive")
		(13 "F.Paste" user "Package Geometry/Pastemask Top")
		(15 "B.Paste" user "Package Geometry/Pastemask Bottom")
		(5 "F.SilkS" user "Ref Des/Silkscreen Top")
		(7 "B.SilkS" user "Ref Des/Silkscreen Bottom")
		(1 "F.Mask" user "Board Geometry/Soldermask Top")
		(3 "B.Mask" user "Board Geometry/Soldermask Bottom")
		(17 "Dwgs.User" user "User.Drawings")
		(19 "Cmts.User" user "User.Comments")
		(21 "Eco1.User" user "User.Eco1")
		(23 "Eco2.User" user "User.Eco2")
		(25 "Edge.Cuts" user "Board Geometry/Outline")
		(27 "Margin" user)
		(31 "F.CrtYd" user "Package Geometry/Place Bound Top")
		(29 "B.CrtYd" user "Package Geometry/Place Bound Bottom")
		(35 "F.Fab" user "Ref Des/Assembly Top")
		(33 "B.Fab" user "Ref Des/Assembly Bottom")
	)
	(footprint ""
		(layer "F.Cu")
		(at 343.789 -23.45436 90)
		(property "Reference" "C7F9"
			(at 0 0 90)
			(layer "F.SilkS")
			(hide yes)
			(effects
				(font
					(size 1.27 1.27)
				)
			)
		)
		(property "Value" ""
			(at 0 0 90)
			(layer "F.Fab")
			(effects
				(font
					(size 1.27 1.27)
				)
			)
		)
		(duplicate_pad_numbers_are_jumpers no)
		(fp_poly
			(pts
				(xy 0.3048 -0.1016) (xy 0.3048 0.9906) (xy -0.3048 0.9906) (xy -0.3048 -0.1016)
			)
			(stroke
				(width 0)
				(type default)
			)
			(fill no)
			(layer "F.CrtYd")
		)
		(fp_line
			(start 0.3048 -0.1016)
			(end -0.3048 -0.1016)
			(stroke
				(width 0.1)
				(type default)
			)
			(layer "F.Fab")
		)
		(fp_line
			(start -0.3048 -0.1016)
			(end -0.3048 0.9906)
			(stroke
				(width 0.1)
				(type default)
			)
			(layer "F.Fab")
		)
		(fp_line
			(start 0.3048 0.9906)
			(end 0.3048 -0.1016)
			(stroke
				(width 0.1)
				(type default)
			)
			(layer "F.Fab")
		)
		(fp_line
			(start -0.3048 0.9906)
			(end 0.3048 0.9906)
			(stroke
				(width 0.1)
				(type default)
			)
			(layer "F.Fab")
		)
		(pad "1" smd rect
			(at 0 0 90)
			(size 0.508 0.508)
			(layers "F.Cu" "F.Mask" "F.Paste")
			(net "VR_FB_PVPP_ABC")
		)
		(pad "2" smd rect
			(at 0 0.889 90)
			(size 0.508 0.508)
			(layers "F.Cu" "F.Mask" "F.Paste")
			(net "VR_COMP_PVPP_ABC_3")
		)
		(zone
			(layer "F.Cu")
			(hatch none 0.5)
			(connect_pads
				(clearance 0)
			)
			(min_thickness 0.25)
			(keepout
				(tracks allowed)
				(vias not_allowed)
				(pads allowed)
				(copperpour not_allowed)
				(footprints allowed)
			)
			(placement
				(enabled no)
				(sheetname "")
			)
			(fill
				(thermal_gap 0.5)
				(thermal_bridge_width 0.5)
				(island_removal_mode 0)
			)
			(polygon
				(pts
					(xy 344.043 -23.20036) (xy 344.043 -23.70836) (xy 344.424 -23.70836) (xy 344.424 -23.20036)
				)
			)
		)
		(zone
			(layer "F.Cu")
			(hatch none 0.5)
			(connect_pads
				(clearance 0)
			)
			(min_thickness 0.25)
			(keepout
				(tracks not_allowed)
				(vias allowed)
				(pads allowed)
				(copperpour not_allowed)
				(footprints allowed)
			)
			(placement
				(enabled no)
				(sheetname "")
			)
			(fill
				(thermal_gap 0.5)
				(thermal_bridge_width 0.5)
				(island_removal_mode 0)
			)
			(polygon
				(pts
					(xy 344.424 -23.20036) (xy 344.424 -23.70836) (xy 344.043 -23.70836) (xy 344.043 -23.20036)
				)
			)
		)
	)
	(footprint ""
		(layer "F.Cu")
		(at 334.518 -11.3792 180)
		(property "Reference" "C7G28"
			(at 3.02133 6.9088 90)
			(unlocked yes)
			(layer "F.SilkS")
			(effects
				(font
					(size 0.7874 0.5842)
					(thickness 0.1524)
				)
			)
		)
		(property "Value" ""
			(at 0 0 180)
			(layer "F.Fab")
			(effects
				(font
					(size 1.27 1.27)
				)
			)
		)
		(duplicate_pad_numbers_are_jumpers no)
		(fp_line
			(start 2.504948 1.633728)
			(end 1.6002 1.633728)
			(stroke
				(width 0.1524)
				(type default)
			)
			(layer "F.SilkS")
		)
		(fp_line
			(start 2.504948 -1.616456)
			(end 2.504948 1.633728)
			(stroke
				(width 0.1524)
				(type default)
			)
			(layer "F.SilkS")
		)
		(fp_line
			(start 2.286 7.366)
			(end 2.286 1.63195)
			(stroke
				(width 0.1524)
				(type default)
			)
			(layer "F.SilkS")
		)
		(fp_line
			(start 2.286 7.366)
			(end 1.600708 7.366)
			(stroke
				(width 0.1524)
				(type default)
			)
			(layer "F.SilkS")
		)
		(fp_line
			(start 1.6002 -1.616456)
			(end 2.504948 -1.616456)
			(stroke
				(width 0.1524)
				(type default)
			)
			(layer "F.SilkS")
		)
		(fp_line
			(start -1.6002 -1.616456)
			(end -2.563114 -1.616456)
			(stroke
				(width 0.1524)
				(type default)
			)
			(layer "F.SilkS")
		)
		(fp_line
			(start -2.286 7.366)
			(end -1.60147 7.366)
			(stroke
				(width 0.1524)
				(type default)
			)
			(layer "F.SilkS")
		)
		(fp_line
			(start -2.286 7.366)
			(end -2.286 1.632712)
			(stroke
				(width 0.1524)
				(type default)
			)
			(layer "F.SilkS")
		)
		(fp_line
			(start -2.563114 1.633728)
			(end -1.6002 1.633728)
			(stroke
				(width 0.1524)
				(type default)
			)
			(layer "F.SilkS")
		)
		(fp_line
			(start -2.563114 -1.616456)
			(end -2.563114 1.633728)
			(stroke
				(width 0.1524)
				(type default)
			)
			(layer "F.SilkS")
		)
		(fp_rect
			(start 2.286 -0.254)
			(end -2.286 7.366)
			(stroke
				(width 0)
				(type default)
			)
			(fill no)
			(layer "F.CrtYd")
		)
		(fp_line
			(start 2.286 7.366)
			(end -2.286 7.366)
			(stroke
				(width 0.1)
				(type default)
			)
			(layer "F.Fab")
		)
		(fp_line
			(start 2.286 -0.254)
			(end 2.286 7.366)
			(stroke
				(width 0.1)
				(type default)
			)
			(layer "F.Fab")
		)
		(fp_line
			(start -2.286 7.366)
			(end -2.286 -0.254)
			(stroke
				(width 0.1)
				(type default)
			)
			(layer "F.Fab")
		)
		(fp_line
			(start -2.286 -0.254)
			(end 2.286 -0.254)
			(stroke
				(width 0.1)
				(type default)
			)
			(layer "F.Fab")
		)
		(pad "1" smd rect
			(at 0 0 180)
			(size 2.54 3.048)
			(layers "F.Cu" "F.Mask" "F.Paste")
			(net "PVDDQ_ABC")
		)
		(pad "2" smd rect
			(at 0 7.112 180)
			(size 2.54 3.048)
			(layers "F.Cu" "F.Mask" "F.Paste")
			(net "GND")
		)
	)
	(footprint ""
		(layer "F.Cu")
		(at 394.9192 -0.2286)
		(property "Reference" "R8G14"
			(at 0 0 0)
			(layer "F.SilkS")
			(hide yes)
			(effects
				(font
					(size 1.27 1.27)
				)
			)
		)
		(property "Value" ""
			(at 0 0 0)
			(layer "F.Fab")
			(effects
				(font
					(size 1.27 1.27)
				)
			)
		)
		(duplicate_pad_numbers_are_jumpers no)
		(fp_poly
			(pts
				(xy -0.2794 -0.1016) (xy 0.2794 -0.1016) (xy 0.2794 0.9906) (xy -0.2794 0.9906)
			)
			(stroke
				(width 0)
				(type default)
			)
			(fill no)
			(layer "F.CrtYd")
		)
		(fp_line
			(start -0.2794 -0.1016)
			(end -0.2794 0.9906)
			(stroke
				(width 0.1)
				(type default)
			)
			(layer "F.Fab")
		)
		(fp_line
			(start -0.2794 0.9906)
			(end 0.2794 0.9906)
			(stroke
				(width 0.1)
				(type default)
			)
			(layer "F.Fab")
		)
		(fp_line
			(start 0.2794 -0.1016)
			(end -0.2794 -0.1016)
			(stroke
				(width 0.1)
				(type default)
			)
			(layer "F.Fab")
		)
		(fp_line
			(start 0.2794 0.9906)
			(end 0.2794 -0.1016)
			(stroke
				(width 0.1)
				(type default)
			)
			(layer "F.Fab")
		)
		(pad "1" smd rect
			(at 0 0)
			(size 0.508 0.508)
			(layers "F.Cu" "F.Mask" "F.Paste")
			(net "JTAG_BMC_TMS")
		)
		(pad "2" smd rect
			(at 0 0.889)
			(size 0.508 0.508)
			(layers "F.Cu" "F.Mask" "F.Paste")
			(net "JTAG_TMS")
		)
		(zone
			(layer "F.Cu")
			(hatch none 0.5)
			(connect_pads
				(clearance 0)
			)
			(min_thickness 0.25)
			(keepout
				(tracks allowed)
				(vias not_allowed)
				(pads allowed)
				(copperpour not_allowed)
				(footprints allowed)
			)
			(placement
				(enabled no)
				(sheetname "")
			)
			(fill
				(thermal_gap 0.5)
				(thermal_bridge_width 0.5)
				(island_removal_mode 0)
			)
			(polygon
				(pts
					(xy 394.6652 0.0254) (xy 395.1732 0.0254) (xy 395.1732 0.4064) (xy 394.6652 0.4064)
				)
			)
		)
		(zone
			(layer "F.Cu")
			(hatch none 0.5)
			(connect_pads
				(clearance 0)
			)
			(min_thickness 0.25)
			(keepout
				(tracks not_allowed)
				(vias allowed)
				(pads allowed)
				(copperpour not_allowed)
				(footprints allowed)
			)
			(placement
				(enabled no)
				(sheetname "")
			)
			(fill
				(thermal_gap 0.5)
				(thermal_bridge_width 0.5)
				(island_removal_mode 0)
			)
			(polygon
				(pts
					(xy 394.6652 0.4064) (xy 395.1732 0.4064) (xy 395.1732 0.0254) (xy 394.6652 0.0254)
				)
			)
		)
	)
)
